(kicad_pcb
	(version 20260206)
	(generator "pcbnew")
	(generator_version "10.0")
	(general
		(thickness 1.6)
		(legacy_teardrops no)
	)
	(paper "A4")
	(title_block
		(title "Bryce Canyon_F.DPB_16315-1-OCP.brd")
		(comment 1 "Bryce Canyon / footprint 993 of 2223 (SAS1), pads 70-142 of 342")
	)
	(layers
		(0 "F.Cu" signal "TOP")
		(4 "In1.Cu" signal "L2GND")
		(6 "In2.Cu" signal "L3")
		(8 "In3.Cu" signal "L4GND")
		(10 "In4.Cu" signal "L5")
		(12 "In5.Cu" signal "L6VCC")
		(14 "In6.Cu" signal "L7VCC")
		(16 "In7.Cu" signal "L8")
		(18 "In8.Cu" signal "L9GND")
		(20 "In9.Cu" signal "L10")
		(22 "In10.Cu" signal "L11GND")
		(2 "B.Cu" signal "BOTTOM")
		(9 "F.Adhes" user "F.Adhesive")
		(11 "B.Adhes" user "B.Adhesive")
		(13 "F.Paste" user "Package Geometry/Pastemask Top")
		(15 "B.Paste" user "Package Geometry/Pastemask Bottom")
		(5 "F.SilkS" user "Ref Des/Silkscreen Top")
		(7 "B.SilkS" user "Ref Des/Silkscreen Bottom")
		(1 "F.Mask" user "Board Geometry/Soldermask Top")
		(3 "B.Mask" user "Board Geometry/Soldermask Bottom")
		(17 "Dwgs.User" user "User.Drawings")
		(19 "Cmts.User" user "User.Comments")
		(21 "Eco1.User" user "User.Eco1")
		(23 "Eco2.User" user "User.Eco2")
		(25 "Edge.Cuts" user "Board Geometry/Outline")
		(27 "Margin" user)
		(31 "F.CrtYd" user "Package Geometry/Place Bound Top")
		(29 "B.CrtYd" user "Package Geometry/Place Bound Bottom")
		(35 "F.Fab" user "Ref Des/Assembly Top")
		(33 "B.Fab" user "Ref Des/Assembly Bottom")
	)
	(footprint ""
		(layer "F.Cu")
		(at 287.83661 -357.705152 -90)
		(property "Reference" "SAS1"
			(at 0 0 270)
			(layer "F.SilkS")
			(hide yes)
			(effects
				(font
					(size 1.27 1.27)
				)
			)
		)
		(property "Value" "AMP-CONN342-10R-2-GP"
			(at 20.955 -16.7386 270)
			(unlocked yes)
			(layer "F.Fab")
			(hide yes)
			(effects
				(font
					(size 1.016 1.016)
					(thickness 0.1524)
				)
			)
		)
		(property "Device Type" "PREFIT-342P-668151H483"
			(at 20.955 -18.2626 270)
			(unlocked yes)
			(layer "F.Fab")
			(hide yes)
			(effects
				(font
					(size 1.016 1.016)
					(thickness 0.1524)
				)
			)
		)
		(duplicate_pad_numbers_are_jumpers no)
		(pad "B34" thru_hole circle
			(at 59.399932 2.400046 270)
			(size 0.762 0.762)
			(drill 0.359918)
			(layers "*.Cu" "*.Mask")
			(remove_unused_layers no)
			(net "PHY_DRV_A_TO_SCC_A_32_DP")
			(clearance 0.1651)
			(thermal_gap 0.1651)
		)
		(pad "B35" thru_hole circle
			(at 61.20003 1.400048 270)
			(size 0.762 0.762)
			(drill 0.359918)
			(layers "*.Cu" "*.Mask")
			(remove_unused_layers no)
			(net "PHY_DRV_A_TO_SCC_A_31_DP")
			(clearance 0.1651)
			(thermal_gap 0.1651)
		)
		(pad "B36" thru_hole circle
			(at 62.999874 2.400046 270)
			(size 0.762 0.762)
			(drill 0.359918)
			(layers "*.Cu" "*.Mask")
			(remove_unused_layers no)
			(net "PHY_DRV_A_TO_SCC_A_30_DP")
			(clearance 0.1651)
			(thermal_gap 0.1651)
		)
		(pad "C1" thru_hole circle
			(at 0 3.599942 270)
			(size 0.762 0.762)
			(drill 0.359918)
			(layers "*.Cu" "*.Mask")
			(remove_unused_layers no)
			(net "SCC_A_STBY_PGOOD")
			(clearance 0.1651)
			(thermal_gap 0.1651)
		)
		(pad "C2" thru_hole circle
			(at 1.800098 4.59994 270)
			(size 0.762 0.762)
			(drill 0.359918)
			(layers "*.Cu" "*.Mask")
			(remove_unused_layers no)
			(net "P3V3_STBY_A")
			(clearance 0.1651)
			(thermal_gap 0.1651)
		)
		(pad "C3" thru_hole circle
			(at 3.599942 3.599942 270)
			(size 0.762 0.762)
			(drill 0.359918)
			(layers "*.Cu" "*.Mask")
			(remove_unused_layers no)
			(net "SCC_A_HEARTBEAT")
			(clearance 0.1651)
			(thermal_gap 0.1651)
		)
		(pad "C4" thru_hole circle
			(at 5.40004 4.59994 270)
			(size 0.762 0.762)
			(drill 0.359918)
			(layers "*.Cu" "*.Mask")
			(remove_unused_layers no)
			(net "SCC_A_SLOT_ID_0")
			(clearance 0.1651)
			(thermal_gap 0.1651)
		)
		(pad "C5" thru_hole circle
			(at 7.199884 3.599942 270)
			(size 0.762 0.762)
			(drill 0.359918)
			(layers "*.Cu" "*.Mask")
			(remove_unused_layers no)
			(net "SCC_A_TYPE_0")
			(clearance 0.1651)
			(thermal_gap 0.1651)
		)
		(pad "C6" thru_hole circle
			(at 8.999982 4.59994 270)
			(size 0.762 0.762)
			(drill 0.359918)
			(layers "*.Cu" "*.Mask")
			(remove_unused_layers no)
			(net "SCC_A_TYPE_2")
			(clearance 0.1651)
			(thermal_gap 0.1651)
		)
		(pad "C7" thru_hole circle
			(at 10.80008 3.599942 270)
			(size 0.762 0.762)
			(drill 0.359918)
			(layers "*.Cu" "*.Mask")
			(remove_unused_layers no)
			(net "UART_SDB_A_TX")
			(clearance 0.1651)
			(thermal_gap 0.1651)
		)
		(pad "C8" thru_hole circle
			(at 12.599924 4.59994 270)
			(size 0.762 0.762)
			(drill 0.359918)
			(layers "*.Cu" "*.Mask")
			(remove_unused_layers no)
			(net "PWM_SCC_A_ZONE_C")
			(clearance 0.1651)
			(thermal_gap 0.1651)
		)
		(pad "C9" thru_hole circle
			(at 14.400022 3.599942 270)
			(size 0.762 0.762)
			(drill 0.359918)
			(layers "*.Cu" "*.Mask")
			(remove_unused_layers no)
			(net "SCC_A_PWR_LED")
			(clearance 0.1651)
			(thermal_gap 0.1651)
		)
		(pad "C10" thru_hole circle
			(at 16.20012 4.59994 270)
			(size 0.762 0.762)
			(drill 0.359918)
			(layers "*.Cu" "*.Mask")
			(remove_unused_layers no)
			(net "SCC_A_FAULT_LED")
			(clearance 0.1651)
			(thermal_gap 0.1651)
		)
		(pad "C11" thru_hole circle
			(at 17.999964 3.599942 270)
			(size 0.762 0.762)
			(drill 0.359918)
			(layers "*.Cu" "*.Mask")
			(remove_unused_layers no)
			(net "DRIVE_INSERT_ALERT_A_N")
			(clearance 0.1651)
			(thermal_gap 0.1651)
		)
		(pad "C12" thru_hole circle
			(at 19.800062 4.59994 270)
			(size 0.762 0.762)
			(drill 0.359918)
			(layers "*.Cu" "*.Mask")
			(remove_unused_layers no)
			(net "I2C_CLIP_A_SCL")
			(clearance 0.1651)
			(thermal_gap 0.1651)
		)
		(pad "C13" thru_hole circle
			(at 21.599906 3.599942 270)
			(size 0.762 0.762)
			(drill 0.359918)
			(layers "*.Cu" "*.Mask")
			(remove_unused_layers no)
			(net "UART_EXP_A_TX")
			(clearance 0.1651)
			(thermal_gap 0.1651)
		)
		(pad "C14" thru_hole circle
			(at 23.400004 4.59994 270)
			(size 0.762 0.762)
			(drill 0.359918)
			(layers "*.Cu" "*.Mask")
			(remove_unused_layers no)
			(net "I2C_DPB_A_SCL_BUF")
			(clearance 0.1651)
			(thermal_gap 0.1651)
		)
		(pad "C15" thru_hole circle
			(at 25.200102 3.599942 270)
			(size 0.762 0.762)
			(drill 0.359918)
			(layers "*.Cu" "*.Mask")
			(remove_unused_layers no)
			(net "I2C_DRIVE_A_PWR_SCL")
			(clearance 0.1651)
			(thermal_gap 0.1651)
		)
		(pad "C16" thru_hole circle
			(at 26.999946 4.59994 270)
			(size 0.762 0.762)
			(drill 0.359918)
			(layers "*.Cu" "*.Mask")
			(remove_unused_layers no)
			(net "I2C_DRIVE_A_INS_SCL")
			(clearance 0.1651)
			(thermal_gap 0.1651)
		)
		(pad "C17" thru_hole circle
			(at 28.800044 3.599942 270)
			(size 0.762 0.762)
			(drill 0.359918)
			(layers "*.Cu" "*.Mask")
			(remove_unused_layers no)
			(net "I2C_DRIVE_A_FLT_LED_SCL")
			(clearance 0.1651)
			(thermal_gap 0.1651)
		)
		(pad "C18" thru_hole circle
			(at 30.599888 4.59994 270)
			(size 0.762 0.762)
			(drill 0.359918)
			(layers "*.Cu" "*.Mask")
			(remove_unused_layers no)
			(net "DRIVE_A_0_ACT")
			(clearance 0.1651)
			(thermal_gap 0.1651)
		)
		(pad "C19" thru_hole circle
			(at 32.399986 3.599942 270)
			(size 0.762 0.762)
			(drill 0.359918)
			(layers "*.Cu" "*.Mask")
			(remove_unused_layers no)
			(net "DRIVE_A_2_ACT")
			(clearance 0.1651)
			(thermal_gap 0.1651)
		)
		(pad "C20" thru_hole circle
			(at 34.200084 4.59994 270)
			(size 0.762 0.762)
			(drill 0.359918)
			(layers "*.Cu" "*.Mask")
			(remove_unused_layers no)
			(net "DRIVE_A_4_ACT")
			(clearance 0.1651)
			(thermal_gap 0.1651)
		)
		(pad "C21" thru_hole circle
			(at 35.999928 3.599942 270)
			(size 0.762 0.762)
			(drill 0.359918)
			(layers "*.Cu" "*.Mask")
			(remove_unused_layers no)
			(net "DRIVE_A_6_ACT")
			(clearance 0.1651)
			(thermal_gap 0.1651)
		)
		(pad "C22" thru_hole circle
			(at 37.800026 4.59994 270)
			(size 0.762 0.762)
			(drill 0.359918)
			(layers "*.Cu" "*.Mask")
			(remove_unused_layers no)
			(net "DRIVE_A_8_ACT")
			(clearance 0.1651)
			(thermal_gap 0.1651)
		)
		(pad "C23" thru_hole circle
			(at 39.600124 3.599942 270)
			(size 0.762 0.762)
			(drill 0.359918)
			(layers "*.Cu" "*.Mask")
			(remove_unused_layers no)
			(net "DRIVE_A_10_ACT")
			(clearance 0.1651)
			(thermal_gap 0.1651)
		)
		(pad "C24" thru_hole circle
			(at 41.399968 4.59994 270)
			(size 0.762 0.762)
			(drill 0.359918)
			(layers "*.Cu" "*.Mask")
			(remove_unused_layers no)
			(net "DRIVE_A_12_ACT")
			(clearance 0.1651)
			(thermal_gap 0.1651)
		)
		(pad "C25" thru_hole circle
			(at 43.200066 3.599942 270)
			(size 0.762 0.762)
			(drill 0.359918)
			(layers "*.Cu" "*.Mask")
			(remove_unused_layers no)
			(net "DRIVE_A_14_ACT")
			(clearance 0.1651)
			(thermal_gap 0.1651)
		)
		(pad "C26" thru_hole circle
			(at 44.99991 4.59994 270)
			(size 0.762 0.762)
			(drill 0.359918)
			(layers "*.Cu" "*.Mask")
			(remove_unused_layers no)
			(net "DRIVE_A_16_ACT")
			(clearance 0.1651)
			(thermal_gap 0.1651)
		)
		(pad "C27" thru_hole circle
			(at 46.800008 3.599942 270)
			(size 0.762 0.762)
			(drill 0.359918)
			(layers "*.Cu" "*.Mask")
			(remove_unused_layers no)
			(net "DRIVE_A_18_ACT")
			(clearance 0.1651)
			(thermal_gap 0.1651)
		)
		(pad "C28" thru_hole circle
			(at 48.600106 4.59994 270)
			(size 0.762 0.762)
			(drill 0.359918)
			(layers "*.Cu" "*.Mask")
			(remove_unused_layers no)
			(net "DRIVE_A_20_ACT")
			(clearance 0.1651)
			(thermal_gap 0.1651)
		)
		(pad "C29" thru_hole circle
			(at 50.39995 3.599942 270)
			(size 0.762 0.762)
			(drill 0.359918)
			(layers "*.Cu" "*.Mask")
			(remove_unused_layers no)
			(net "DRIVE_A_22_ACT")
			(clearance 0.1651)
			(thermal_gap 0.1651)
		)
		(pad "C30" thru_hole circle
			(at 52.200048 4.59994 270)
			(size 0.762 0.762)
			(drill 0.359918)
			(layers "*.Cu" "*.Mask")
			(remove_unused_layers no)
			(net "DRIVE_A_24_ACT")
			(clearance 0.1651)
			(thermal_gap 0.1651)
		)
		(pad "C31" thru_hole circle
			(at 53.999892 3.599942 270)
			(size 0.762 0.762)
			(drill 0.359918)
			(layers "*.Cu" "*.Mask")
			(remove_unused_layers no)
			(net "DRIVE_A_26_ACT")
			(clearance 0.1651)
			(thermal_gap 0.1651)
		)
		(pad "C32" thru_hole circle
			(at 55.79999 4.59994 270)
			(size 0.762 0.762)
			(drill 0.359918)
			(layers "*.Cu" "*.Mask")
			(remove_unused_layers no)
			(net "DRIVE_A_28_ACT")
			(clearance 0.1651)
			(thermal_gap 0.1651)
		)
		(pad "C33" thru_hole circle
			(at 57.600088 3.599942 270)
			(size 0.762 0.762)
			(drill 0.359918)
			(layers "*.Cu" "*.Mask")
			(remove_unused_layers no)
			(net "DRIVE_A_30_ACT")
			(clearance 0.1651)
			(thermal_gap 0.1651)
		)
		(pad "C34" thru_hole circle
			(at 59.399932 4.59994 270)
			(size 0.762 0.762)
			(drill 0.359918)
			(layers "*.Cu" "*.Mask")
			(remove_unused_layers no)
			(net "DRIVE_A_32_ACT")
			(clearance 0.1651)
			(thermal_gap 0.1651)
		)
		(pad "C35" thru_hole circle
			(at 61.20003 3.599942 270)
			(size 0.762 0.762)
			(drill 0.359918)
			(layers "*.Cu" "*.Mask")
			(remove_unused_layers no)
			(net "DRIVE_A_34_ACT")
			(clearance 0.1651)
			(thermal_gap 0.1651)
		)
		(pad "C36" thru_hole circle
			(at 62.999874 4.59994 270)
			(size 0.762 0.762)
			(drill 0.359918)
			(layers "*.Cu" "*.Mask")
			(remove_unused_layers no)
			(net "SCC_A_HS_EN")
			(clearance 0.1651)
			(thermal_gap 0.1651)
		)
		(pad "D1" thru_hole circle
			(at 0 4.99999 270)
			(size 0.762 0.762)
			(drill 0.359918)
			(layers "*.Cu" "*.Mask")
			(remove_unused_layers no)
			(net "BMC_A_HEARTBEAT")
			(clearance 0.1651)
			(thermal_gap 0.1651)
		)
		(pad "D2" thru_hole circle
			(at 1.800098 5.999988 270)
			(size 0.762 0.762)
			(drill 0.359918)
			(layers "*.Cu" "*.Mask")
			(remove_unused_layers no)
			(net "SCC_A_STBY_PWR_EN")
			(clearance 0.1651)
			(thermal_gap 0.1651)
		)
		(pad "D3" thru_hole circle
			(at 3.599942 4.99999 270)
			(size 0.762 0.762)
			(drill 0.359918)
			(layers "*.Cu" "*.Mask")
			(remove_unused_layers no)
			(net "SCC_B_HEARTBEAT")
			(clearance 0.1651)
			(thermal_gap 0.1651)
		)
		(pad "D4" thru_hole circle
			(at 5.40004 5.999988 270)
			(size 0.762 0.762)
			(drill 0.359918)
			(layers "*.Cu" "*.Mask")
			(remove_unused_layers no)
			(net "SCC_A_SLOT_ID_1")
			(clearance 0.1651)
			(thermal_gap 0.1651)
		)
		(pad "D5" thru_hole circle
			(at 7.199884 4.99999 270)
			(size 0.762 0.762)
			(drill 0.359918)
			(layers "*.Cu" "*.Mask")
			(remove_unused_layers no)
			(net "SCC_A_TYPE_1")
			(clearance 0.1651)
			(thermal_gap 0.1651)
		)
		(pad "D6" thru_hole circle
			(at 8.999982 5.999988 270)
			(size 0.762 0.762)
			(drill 0.359918)
			(layers "*.Cu" "*.Mask")
			(remove_unused_layers no)
			(net "SCC_A_TYPE_3")
			(clearance 0.1651)
			(thermal_gap 0.1651)
		)
		(pad "D7" thru_hole circle
			(at 10.80008 4.99999 270)
			(size 0.762 0.762)
			(drill 0.359918)
			(layers "*.Cu" "*.Mask")
			(remove_unused_layers no)
			(net "UART_SDB_A_RX")
			(clearance 0.1651)
			(thermal_gap 0.1651)
		)
		(pad "D8" thru_hole circle
			(at 12.599924 5.999988 270)
			(size 0.762 0.762)
			(drill 0.359918)
			(layers "*.Cu" "*.Mask")
			(remove_unused_layers no)
			(net "PWM_SCC_A_ZONE_D")
			(clearance 0.1651)
			(thermal_gap 0.1651)
		)
		(pad "D9" thru_hole circle
			(at 14.400022 4.99999 270)
			(size 0.762 0.762)
			(drill 0.359918)
			(layers "*.Cu" "*.Mask")
			(remove_unused_layers no)
			(net "SCC_A_FULL_PWR_EN")
			(clearance 0.1651)
			(thermal_gap 0.1651)
		)
		(pad "D10" thru_hole circle
			(at 16.20012 5.999988 270)
			(size 0.762 0.762)
			(drill 0.359918)
			(layers "*.Cu" "*.Mask")
			(remove_unused_layers no)
			(net "SCC_A_RESET_N")
			(clearance 0.1651)
			(thermal_gap 0.1651)
		)
		(pad "D11" thru_hole circle
			(at 17.999964 4.99999 270)
			(size 0.762 0.762)
			(drill 0.359918)
			(layers "*.Cu" "*.Mask")
			(remove_unused_layers no)
			(net "SCC_A_INS_N")
			(clearance 0.1651)
			(thermal_gap 0.1651)
		)
		(pad "D12" thru_hole circle
			(at 19.800062 5.999988 270)
			(size 0.762 0.762)
			(drill 0.359918)
			(layers "*.Cu" "*.Mask")
			(remove_unused_layers no)
			(net "I2C_CLIP_A_SDA")
			(clearance 0.1651)
			(thermal_gap 0.1651)
		)
		(pad "D13" thru_hole circle
			(at 21.599906 4.99999 270)
			(size 0.762 0.762)
			(drill 0.359918)
			(layers "*.Cu" "*.Mask")
			(remove_unused_layers no)
			(net "UART_EXP_A_RX")
			(clearance 0.1651)
			(thermal_gap 0.1651)
		)
		(pad "D14" thru_hole circle
			(at 23.400004 5.999988 270)
			(size 0.762 0.762)
			(drill 0.359918)
			(layers "*.Cu" "*.Mask")
			(remove_unused_layers no)
			(net "I2C_DPB_A_SDA_BUF")
			(clearance 0.1651)
			(thermal_gap 0.1651)
		)
		(pad "D15" thru_hole circle
			(at 25.200102 4.99999 270)
			(size 0.762 0.762)
			(drill 0.359918)
			(layers "*.Cu" "*.Mask")
			(remove_unused_layers no)
			(net "I2C_DRIVE_A_PWR_SDA")
			(clearance 0.1651)
			(thermal_gap 0.1651)
		)
		(pad "D16" thru_hole circle
			(at 26.999946 5.999988 270)
			(size 0.762 0.762)
			(drill 0.359918)
			(layers "*.Cu" "*.Mask")
			(remove_unused_layers no)
			(net "I2C_DRIVE_A_INS_SDA")
			(clearance 0.1651)
			(thermal_gap 0.1651)
		)
		(pad "D17" thru_hole circle
			(at 28.800044 4.99999 270)
			(size 0.762 0.762)
			(drill 0.359918)
			(layers "*.Cu" "*.Mask")
			(remove_unused_layers no)
			(net "I2C_DRIVE_A_FLT_LED_SDA")
			(clearance 0.1651)
			(thermal_gap 0.1651)
		)
		(pad "D18" thru_hole circle
			(at 30.599888 5.999988 270)
			(size 0.762 0.762)
			(drill 0.359918)
			(layers "*.Cu" "*.Mask")
			(remove_unused_layers no)
			(net "DRIVE_A_1_ACT")
			(clearance 0.1651)
			(thermal_gap 0.1651)
		)
		(pad "D19" thru_hole circle
			(at 32.399986 4.99999 270)
			(size 0.762 0.762)
			(drill 0.359918)
			(layers "*.Cu" "*.Mask")
			(remove_unused_layers no)
			(net "DRIVE_A_3_ACT")
			(clearance 0.1651)
			(thermal_gap 0.1651)
		)
		(pad "D20" thru_hole circle
			(at 34.200084 5.999988 270)
			(size 0.762 0.762)
			(drill 0.359918)
			(layers "*.Cu" "*.Mask")
			(remove_unused_layers no)
			(net "DRIVE_A_5_ACT")
			(clearance 0.1651)
			(thermal_gap 0.1651)
		)
		(pad "D21" thru_hole circle
			(at 35.999928 4.99999 270)
			(size 0.762 0.762)
			(drill 0.359918)
			(layers "*.Cu" "*.Mask")
			(remove_unused_layers no)
			(net "DRIVE_A_7_ACT")
			(clearance 0.1651)
			(thermal_gap 0.1651)
		)
		(pad "D22" thru_hole circle
			(at 37.800026 5.999988 270)
			(size 0.762 0.762)
			(drill 0.359918)
			(layers "*.Cu" "*.Mask")
			(remove_unused_layers no)
			(net "DRIVE_A_9_ACT")
			(clearance 0.1651)
			(thermal_gap 0.1651)
		)
		(pad "D23" thru_hole circle
			(at 39.600124 4.99999 270)
			(size 0.762 0.762)
			(drill 0.359918)
			(layers "*.Cu" "*.Mask")
			(remove_unused_layers no)
			(net "DRIVE_A_11_ACT")
			(clearance 0.1651)
			(thermal_gap 0.1651)
		)
		(pad "D24" thru_hole circle
			(at 41.399968 5.999988 270)
			(size 0.762 0.762)
			(drill 0.359918)
			(layers "*.Cu" "*.Mask")
			(remove_unused_layers no)
			(net "DRIVE_A_13_ACT")
			(clearance 0.1651)
			(thermal_gap 0.1651)
		)
		(pad "D25" thru_hole circle
			(at 43.200066 4.99999 270)
			(size 0.762 0.762)
			(drill 0.359918)
			(layers "*.Cu" "*.Mask")
			(remove_unused_layers no)
			(net "DRIVE_A_15_ACT")
			(clearance 0.1651)
			(thermal_gap 0.1651)
		)
		(pad "D26" thru_hole circle
			(at 44.99991 5.999988 270)
			(size 0.762 0.762)
			(drill 0.359918)
			(layers "*.Cu" "*.Mask")
			(remove_unused_layers no)
			(net "DRIVE_A_17_ACT")
			(clearance 0.1651)
			(thermal_gap 0.1651)
		)
		(pad "D27" thru_hole circle
			(at 46.800008 4.99999 270)
			(size 0.762 0.762)
			(drill 0.359918)
			(layers "*.Cu" "*.Mask")
			(remove_unused_layers no)
			(net "DRIVE_A_19_ACT")
			(clearance 0.1651)
			(thermal_gap 0.1651)
		)
		(pad "D28" thru_hole circle
			(at 48.600106 5.999988 270)
			(size 0.762 0.762)
			(drill 0.359918)
			(layers "*.Cu" "*.Mask")
			(remove_unused_layers no)
			(net "DRIVE_A_21_ACT")
			(clearance 0.1651)
			(thermal_gap 0.1651)
		)
		(pad "D29" thru_hole circle
			(at 50.39995 4.99999 270)
			(size 0.762 0.762)
			(drill 0.359918)
			(layers "*.Cu" "*.Mask")
			(remove_unused_layers no)
			(net "DRIVE_A_23_ACT")
			(clearance 0.1651)
			(thermal_gap 0.1651)
		)
		(pad "D30" thru_hole circle
			(at 52.200048 5.999988 270)
			(size 0.762 0.762)
			(drill 0.359918)
			(layers "*.Cu" "*.Mask")
			(remove_unused_layers no)
			(net "DRIVE_A_25_ACT")
			(clearance 0.1651)
			(thermal_gap 0.1651)
		)
		(pad "D31" thru_hole circle
			(at 53.999892 4.99999 270)
			(size 0.762 0.762)
			(drill 0.359918)
			(layers "*.Cu" "*.Mask")
			(remove_unused_layers no)
			(net "DRIVE_A_27_ACT")
			(clearance 0.1651)
			(thermal_gap 0.1651)
		)
		(pad "D32" thru_hole circle
			(at 55.79999 5.999988 270)
			(size 0.762 0.762)
			(drill 0.359918)
			(layers "*.Cu" "*.Mask")
			(remove_unused_layers no)
			(net "DRIVE_A_29_ACT")
			(clearance 0.1651)
			(thermal_gap 0.1651)
		)
		(pad "D33" thru_hole circle
			(at 57.600088 4.99999 270)
			(size 0.762 0.762)
			(drill 0.359918)
			(layers "*.Cu" "*.Mask")
			(remove_unused_layers no)
			(net "DRIVE_A_31_ACT")
			(clearance 0.1651)
			(thermal_gap 0.1651)
		)
		(pad "D34" thru_hole circle
			(at 59.399932 5.999988 270)
			(size 0.762 0.762)
			(drill 0.359918)
			(layers "*.Cu" "*.Mask")
			(remove_unused_layers no)
			(net "DRIVE_A_33_ACT")
			(clearance 0.1651)
			(thermal_gap 0.1651)
		)
	)
)
